(kicad_pcb
	(version 20260206)
	(generator "pcbnew")
	(generator_version "10.0")
	(general
		(thickness 1.6)
		(legacy_teardrops no)
	)
	(paper "A4")
	(title_block
		(title "panther-plus-userver — 13130-1b_20150205.brd")
		(comment 1 "Honey Badger (Wiwynn) / footprint 894 of 1509 (DIMM1), pads 86-92 of 210")
	)
	(layers
		(0 "F.Cu" signal "TOP")
		(4 "In1.Cu" signal "L2")
		(6 "In2.Cu" signal "L3")
		(8 "In3.Cu" signal "L4")
		(10 "In4.Cu" signal "L5")
		(12 "In5.Cu" signal "L6")
		(14 "In6.Cu" signal "L7")
		(16 "In7.Cu" signal "L8")
		(18 "In8.Cu" signal "L9")
		(20 "In9.Cu" signal "L10")
		(22 "In10.Cu" signal "L11")
		(2 "B.Cu" signal "BOTTOM")
		(9 "F.Adhes" user "F.Adhesive")
		(11 "B.Adhes" user "B.Adhesive")
		(13 "F.Paste" user "Package Geometry/Pastemask Top")
		(15 "B.Paste" user "Package Geometry/Pastemask Bottom")
		(5 "F.SilkS" user "Ref Des/Silkscreen Top")
		(7 "B.SilkS" user "Ref Des/Silkscreen Bottom")
		(1 "F.Mask" user "Board Geometry/Soldermask Top")
		(3 "B.Mask" user "Board Geometry/Soldermask Bottom")
		(17 "Dwgs.User" user "User.Drawings")
		(19 "Cmts.User" user "User.Comments")
		(21 "Eco1.User" user "User.Eco1")
		(23 "Eco2.User" user "User.Eco2")
		(25 "Edge.Cuts" user "Board Geometry/Outline")
		(27 "Margin" user)
		(31 "F.CrtYd" user "Package Geometry/Place Bound Top")
		(29 "B.CrtYd" user "Package Geometry/Place Bound Bottom")
		(35 "F.Fab" user "Ref Des/Assembly Top")
		(33 "B.Fab" user "Ref Des/Assembly Bottom")
	)
	(footprint ""
		(layer "B.Cu")
		(at 158.500064 -66.699892 180)
		(property "Reference" "DIMM1"
			(at 0 0 0)
			(layer "B.SilkS")
			(hide yes)
			(effects
				(font
					(size 1.27 1.27)
				)
				(justify mirror)
			)
		)
		(property "Value" "DDR3-204P-142-COLAY-1-GP-U"
			(at 41.312338 -16.676878 180)
			(unlocked yes)
			(layer "B.Fab")
			(hide yes)
			(effects
				(font
					(size 1.016 1.016)
					(thickness 0.1524)
				)
				(justify mirror)
			)
		)
		(property "Device Type" "AS0A626-J8R6-7H-COLAY-1"
			(at 41.312338 -18.200878 180)
			(unlocked yes)
			(layer "B.Fab")
			(hide yes)
			(effects
				(font
					(size 1.016 1.016)
					(thickness 0.1524)
				)
				(justify mirror)
			)
		)
		(duplicate_pad_numbers_are_jumpers no)
		(pad "84" smd custom
			(at -4.350004 4.100068)
			(size 0.1143 0.1143)
			(layers "B.Cu" "B.Mask" "B.Paste")
			(net "DDR3_M_A_VREF_CA")
			(options
				(clearance outline)
				(anchor circle)
			)
			(primitives
				(gr_poly
					(pts
						(xy 0 -0.9017) (xy -0.03175 -0.89916) (xy -0.0635 -0.889) (xy -0.09144 -0.87376) (xy -0.11684 -0.85344)
						(xy -0.13716 -0.82804) (xy -0.1524 -0.8001) (xy -0.16256 -0.76835) (xy -0.1651 -0.7366) (xy -0.1651 -0.11938)
						(xy -0.17272 -0.11176) (xy -0.19812 -0.0762) (xy -0.2032 -0.06604) (xy -0.20701 -0.05715) (xy -0.21209 -0.04699)
						(xy -0.2159 -0.03683) (xy -0.21844 -0.02667) (xy -0.22225 -0.01524) (xy -0.22352 -0.00508) (xy -0.22606 0.00508)
						(xy -0.22733 0.01651) (xy -0.22733 0.02667) (xy -0.2286 0.0381) (xy -0.22733 0.04953) (xy -0.22733 0.05969)
						(xy -0.22606 0.07112) (xy -0.22352 0.08128) (xy -0.22225 0.09144) (xy -0.21844 0.10287) (xy -0.2159 0.11303)
						(xy -0.21209 0.12319) (xy -0.20701 0.13335) (xy -0.2032 0.14224) (xy -0.19812 0.1524) (xy -0.17272 0.18796)
						(xy -0.1651 0.19558) (xy -0.1651 0.7366) (xy -0.16256 0.76835) (xy -0.1524 0.8001) (xy -0.13716 0.82804)
						(xy -0.11684 0.85344) (xy -0.09144 0.87376) (xy -0.0635 0.889) (xy -0.03175 0.89916) (xy 0 0.9017)
						(xy 0.03175 0.89916) (xy 0.0635 0.889) (xy 0.09144 0.87376) (xy 0.11684 0.85344) (xy 0.13716 0.82804)
						(xy 0.1524 0.8001) (xy 0.16256 0.76835) (xy 0.1651 0.7366) (xy 0.1651 0.19685) (xy 0.17272 0.18923)
						(xy 0.17907 0.18034) (xy 0.18669 0.17145) (xy 0.19177 0.16256) (xy 0.19812 0.15367) (xy 0.20828 0.13335)
						(xy 0.21971 0.10287) (xy 0.22225 0.09271) (xy 0.22479 0.08128) (xy 0.22606 0.07112) (xy 0.2286 0.05969)
						(xy 0.2286 0.01651) (xy 0.22606 0.00508) (xy 0.22479 -0.00508) (xy 0.22225 -0.01651) (xy 0.21971 -0.02667)
						(xy 0.20828 -0.05715) (xy 0.19812 -0.07747) (xy 0.19177 -0.08636) (xy 0.18669 -0.09525) (xy 0.17907 -0.10414)
						(xy 0.17272 -0.11303) (xy 0.1651 -0.12065) (xy 0.1651 -0.7366) (xy 0.16256 -0.76835) (xy 0.1524 -0.8001)
						(xy 0.13716 -0.82804) (xy 0.11684 -0.85344) (xy 0.09144 -0.87376) (xy 0.0635 -0.889) (xy 0.03175 -0.89916)
					)
					(width 0)
					(fill yes)
				)
			)
		)
		(pad "85" smd custom
			(at -4.05003 -4.100068)
			(size 0.1143 0.1143)
			(layers "B.Cu" "B.Mask" "B.Paste")
			(net "PV_VDDR")
			(options
				(clearance outline)
				(anchor circle)
			)
			(primitives
				(gr_poly
					(pts
						(xy 0 -0.9017) (xy -0.03175 -0.89916) (xy -0.0635 -0.889) (xy -0.09144 -0.87376) (xy -0.11684 -0.85344)
						(xy -0.13716 -0.82804) (xy -0.1524 -0.8001) (xy -0.16256 -0.76835) (xy -0.1651 -0.7366) (xy -0.1651 -0.44958)
						(xy -0.17272 -0.44196) (xy -0.19812 -0.4064) (xy -0.2032 -0.39624) (xy -0.20701 -0.38735) (xy -0.21209 -0.37719)
						(xy -0.2159 -0.36703) (xy -0.21844 -0.35687) (xy -0.22225 -0.34544) (xy -0.22352 -0.33528) (xy -0.22606 -0.32512)
						(xy -0.22733 -0.31369) (xy -0.22733 -0.30353) (xy -0.2286 -0.2921) (xy -0.22733 -0.28067) (xy -0.22733 -0.27051)
						(xy -0.22606 -0.25908) (xy -0.22352 -0.24892) (xy -0.22225 -0.23876) (xy -0.21844 -0.22733) (xy -0.2159 -0.21717)
						(xy -0.21209 -0.20701) (xy -0.20701 -0.19685) (xy -0.2032 -0.18796) (xy -0.19812 -0.1778) (xy -0.17272 -0.14224)
						(xy -0.1651 -0.13462) (xy -0.1651 0.7366) (xy -0.16256 0.76835) (xy -0.1524 0.8001) (xy -0.13716 0.82804)
						(xy -0.11684 0.85344) (xy -0.09144 0.87376) (xy -0.0635 0.889) (xy -0.03175 0.89916) (xy 0 0.9017)
						(xy 0.03175 0.89916) (xy 0.0635 0.889) (xy 0.09144 0.87376) (xy 0.11684 0.85344) (xy 0.13716 0.82804)
						(xy 0.1524 0.8001) (xy 0.16256 0.76835) (xy 0.1651 0.7366) (xy 0.1651 -0.13462) (xy 0.17272 -0.14224)
						(xy 0.19812 -0.1778) (xy 0.2032 -0.18796) (xy 0.20701 -0.19685) (xy 0.21209 -0.20701) (xy 0.2159 -0.21717)
						(xy 0.21844 -0.22733) (xy 0.22225 -0.23876) (xy 0.22352 -0.24892) (xy 0.22606 -0.25908) (xy 0.22733 -0.27051)
						(xy 0.22733 -0.28067) (xy 0.2286 -0.2921) (xy 0.22733 -0.30353) (xy 0.22733 -0.31369) (xy 0.22606 -0.32512)
						(xy 0.22352 -0.33528) (xy 0.22225 -0.34544) (xy 0.21844 -0.35687) (xy 0.2159 -0.36703) (xy 0.21209 -0.37719)
						(xy 0.20701 -0.38735) (xy 0.2032 -0.39624) (xy 0.19812 -0.4064) (xy 0.17272 -0.44196) (xy 0.1651 -0.44958)
						(xy 0.1651 -0.7366) (xy 0.16256 -0.76835) (xy 0.1524 -0.8001) (xy 0.13716 -0.82804) (xy 0.11684 -0.85344)
						(xy 0.09144 -0.87376) (xy 0.0635 -0.889) (xy 0.03175 -0.89916)
					)
					(width 0)
					(fill yes)
				)
			)
		)
		(pad "86" smd custom
			(at -3.750056 4.100068)
			(size 0.1143 0.1143)
			(layers "B.Cu" "B.Mask" "B.Paste")
			(net "PV_VDDR")
			(options
				(clearance outline)
				(anchor circle)
			)
			(primitives
				(gr_poly
					(pts
						(xy 0 -0.9017) (xy -0.03175 -0.89916) (xy -0.0635 -0.889) (xy -0.09144 -0.87376) (xy -0.11684 -0.85344)
						(xy -0.13716 -0.82804) (xy -0.1524 -0.8001) (xy -0.16256 -0.76835) (xy -0.1651 -0.7366) (xy -0.1651 0.13462)
						(xy -0.17272 0.14224) (xy -0.19812 0.1778) (xy -0.2032 0.18796) (xy -0.20701 0.19685) (xy -0.21209 0.20701)
						(xy -0.2159 0.21717) (xy -0.21844 0.22733) (xy -0.22225 0.23876) (xy -0.22352 0.24892) (xy -0.22606 0.25908)
						(xy -0.22733 0.27051) (xy -0.22733 0.28067) (xy -0.2286 0.2921) (xy -0.22733 0.30353) (xy -0.22733 0.31369)
						(xy -0.22606 0.32512) (xy -0.22352 0.33528) (xy -0.22225 0.34544) (xy -0.21844 0.35687) (xy -0.2159 0.36703)
						(xy -0.21209 0.37719) (xy -0.20701 0.38735) (xy -0.2032 0.39624) (xy -0.19812 0.4064) (xy -0.17272 0.44196)
						(xy -0.1651 0.44958) (xy -0.1651 0.7366) (xy -0.16256 0.76835) (xy -0.1524 0.8001) (xy -0.13716 0.82804)
						(xy -0.11684 0.85344) (xy -0.09144 0.87376) (xy -0.0635 0.889) (xy -0.03175 0.89916) (xy 0 0.9017)
						(xy 0.03175 0.89916) (xy 0.0635 0.889) (xy 0.09144 0.87376) (xy 0.11684 0.85344) (xy 0.13716 0.82804)
						(xy 0.1524 0.8001) (xy 0.16256 0.76835) (xy 0.1651 0.7366) (xy 0.1651 0.44958) (xy 0.17272 0.44196)
						(xy 0.19812 0.4064) (xy 0.2032 0.39624) (xy 0.20701 0.38735) (xy 0.21209 0.37719) (xy 0.2159 0.36703)
						(xy 0.21844 0.35687) (xy 0.22225 0.34544) (xy 0.22352 0.33528) (xy 0.22606 0.32512) (xy 0.22733 0.31369)
						(xy 0.22733 0.30353) (xy 0.2286 0.2921) (xy 0.22733 0.28067) (xy 0.22733 0.27051) (xy 0.22606 0.25908)
						(xy 0.22352 0.24892) (xy 0.22225 0.23876) (xy 0.21844 0.22733) (xy 0.2159 0.21717) (xy 0.21209 0.20701)
						(xy 0.20701 0.19685) (xy 0.2032 0.18796) (xy 0.19812 0.1778) (xy 0.17272 0.14224) (xy 0.1651 0.13462)
						(xy 0.1651 -0.7366) (xy 0.16256 -0.76835) (xy 0.1524 -0.8001) (xy 0.13716 -0.82804) (xy 0.11684 -0.85344)
						(xy 0.09144 -0.87376) (xy 0.0635 -0.889) (xy 0.03175 -0.89916)
					)
					(width 0)
					(fill yes)
				)
			)
		)
		(pad "87" smd custom
			(at -3.450082 -4.100068)
			(size 0.1143 0.1143)
			(layers "B.Cu" "B.Mask" "B.Paste")
			(net "M_A_CKE0")
			(options
				(clearance outline)
				(anchor circle)
			)
			(primitives
				(gr_poly
					(pts
						(xy 0 -0.9017) (xy -0.03175 -0.89916) (xy -0.0635 -0.889) (xy -0.09144 -0.87376) (xy -0.11684 -0.85344)
						(xy -0.13716 -0.82804) (xy -0.1524 -0.8001) (xy -0.16256 -0.76835) (xy -0.1651 -0.7366) (xy -0.1651 -0.19685)
						(xy -0.17272 -0.18923) (xy -0.17907 -0.18034) (xy -0.18669 -0.17145) (xy -0.19177 -0.16256) (xy -0.19812 -0.15367)
						(xy -0.20828 -0.13335) (xy -0.21971 -0.10287) (xy -0.22225 -0.09271) (xy -0.22479 -0.08128) (xy -0.22606 -0.07112)
						(xy -0.2286 -0.05969) (xy -0.2286 -0.01651) (xy -0.22606 -0.00508) (xy -0.22479 0.00508) (xy -0.22225 0.01651)
						(xy -0.21971 0.02667) (xy -0.20828 0.05715) (xy -0.19812 0.07747) (xy -0.19177 0.08636) (xy -0.18669 0.09525)
						(xy -0.17907 0.10414) (xy -0.17272 0.11303) (xy -0.1651 0.12065) (xy -0.1651 0.7366) (xy -0.16256 0.76835)
						(xy -0.1524 0.8001) (xy -0.13716 0.82804) (xy -0.11684 0.85344) (xy -0.09144 0.87376) (xy -0.0635 0.889)
						(xy -0.03175 0.89916) (xy 0 0.9017) (xy 0.03175 0.89916) (xy 0.0635 0.889) (xy 0.09144 0.87376)
						(xy 0.11684 0.85344) (xy 0.13716 0.82804) (xy 0.1524 0.8001) (xy 0.16256 0.76835) (xy 0.1651 0.7366)
						(xy 0.1651 0.11938) (xy 0.17272 0.11176) (xy 0.19812 0.0762) (xy 0.2032 0.06604) (xy 0.20701 0.05715)
						(xy 0.21209 0.04699) (xy 0.2159 0.03683) (xy 0.21844 0.02667) (xy 0.22225 0.01524) (xy 0.22352 0.00508)
						(xy 0.22606 -0.00508) (xy 0.22733 -0.01651) (xy 0.22733 -0.02667) (xy 0.2286 -0.0381) (xy 0.22733 -0.04953)
						(xy 0.22733 -0.05969) (xy 0.22606 -0.07112) (xy 0.22352 -0.08128) (xy 0.22225 -0.09144) (xy 0.21844 -0.10287)
						(xy 0.2159 -0.11303) (xy 0.21209 -0.12319) (xy 0.20701 -0.13335) (xy 0.2032 -0.14224) (xy 0.19812 -0.1524)
						(xy 0.17272 -0.18796) (xy 0.1651 -0.19558) (xy 0.1651 -0.7366) (xy 0.16256 -0.76835) (xy 0.1524 -0.8001)
						(xy 0.13716 -0.82804) (xy 0.11684 -0.85344) (xy 0.09144 -0.87376) (xy 0.0635 -0.889) (xy 0.03175 -0.89916)
					)
					(width 0)
					(fill yes)
				)
			)
		)
		(pad "88" smd custom
			(at -3.150108 4.100068)
			(size 0.1143 0.1143)
			(layers "B.Cu" "B.Mask" "B.Paste")
			(net "M_A_MA15")
			(options
				(clearance outline)
				(anchor circle)
			)
			(primitives
				(gr_poly
					(pts
						(xy 0 -0.9017) (xy -0.03175 -0.89916) (xy -0.0635 -0.889) (xy -0.09144 -0.87376) (xy -0.11684 -0.85344)
						(xy -0.13716 -0.82804) (xy -0.1524 -0.8001) (xy -0.16256 -0.76835) (xy -0.1651 -0.7366) (xy -0.1651 -0.11938)
						(xy -0.17272 -0.11176) (xy -0.19812 -0.0762) (xy -0.2032 -0.06604) (xy -0.20701 -0.05715) (xy -0.21209 -0.04699)
						(xy -0.2159 -0.03683) (xy -0.21844 -0.02667) (xy -0.22225 -0.01524) (xy -0.22352 -0.00508) (xy -0.22606 0.00508)
						(xy -0.22733 0.01651) (xy -0.22733 0.02667) (xy -0.2286 0.0381) (xy -0.22733 0.04953) (xy -0.22733 0.05969)
						(xy -0.22606 0.07112) (xy -0.22352 0.08128) (xy -0.22225 0.09144) (xy -0.21844 0.10287) (xy -0.2159 0.11303)
						(xy -0.21209 0.12319) (xy -0.20701 0.13335) (xy -0.2032 0.14224) (xy -0.19812 0.1524) (xy -0.17272 0.18796)
						(xy -0.1651 0.19558) (xy -0.1651 0.7366) (xy -0.16256 0.76835) (xy -0.1524 0.8001) (xy -0.13716 0.82804)
						(xy -0.11684 0.85344) (xy -0.09144 0.87376) (xy -0.0635 0.889) (xy -0.03175 0.89916) (xy 0 0.9017)
						(xy 0.03175 0.89916) (xy 0.0635 0.889) (xy 0.09144 0.87376) (xy 0.11684 0.85344) (xy 0.13716 0.82804)
						(xy 0.1524 0.8001) (xy 0.16256 0.76835) (xy 0.1651 0.7366) (xy 0.1651 0.19685) (xy 0.17272 0.18923)
						(xy 0.17907 0.18034) (xy 0.18669 0.17145) (xy 0.19177 0.16256) (xy 0.19812 0.15367) (xy 0.20828 0.13335)
						(xy 0.21971 0.10287) (xy 0.22225 0.09271) (xy 0.22479 0.08128) (xy 0.22606 0.07112) (xy 0.2286 0.05969)
						(xy 0.2286 0.01651) (xy 0.22606 0.00508) (xy 0.22479 -0.00508) (xy 0.22225 -0.01651) (xy 0.21971 -0.02667)
						(xy 0.20828 -0.05715) (xy 0.19812 -0.07747) (xy 0.19177 -0.08636) (xy 0.18669 -0.09525) (xy 0.17907 -0.10414)
						(xy 0.17272 -0.11303) (xy 0.1651 -0.12065) (xy 0.1651 -0.7366) (xy 0.16256 -0.76835) (xy 0.1524 -0.8001)
						(xy 0.13716 -0.82804) (xy 0.11684 -0.85344) (xy 0.09144 -0.87376) (xy 0.0635 -0.889) (xy 0.03175 -0.89916)
					)
					(width 0)
					(fill yes)
				)
			)
		)
		(pad "89" smd custom
			(at -2.84988 -4.100068)
			(size 0.1143 0.1143)
			(layers "B.Cu" "B.Mask" "B.Paste")
			(net "M_A_CKE1")
			(options
				(clearance outline)
				(anchor circle)
			)
			(primitives
				(gr_poly
					(pts
						(xy 0 -0.9017) (xy -0.03175 -0.89916) (xy -0.0635 -0.889) (xy -0.09144 -0.87376) (xy -0.11684 -0.85344)
						(xy -0.13716 -0.82804) (xy -0.1524 -0.8001) (xy -0.16256 -0.76835) (xy -0.1651 -0.7366) (xy -0.1651 -0.44958)
						(xy -0.17272 -0.44196) (xy -0.19812 -0.4064) (xy -0.2032 -0.39624) (xy -0.20701 -0.38735) (xy -0.21209 -0.37719)
						(xy -0.2159 -0.36703) (xy -0.21844 -0.35687) (xy -0.22225 -0.34544) (xy -0.22352 -0.33528) (xy -0.22606 -0.32512)
						(xy -0.22733 -0.31369) (xy -0.22733 -0.30353) (xy -0.2286 -0.2921) (xy -0.22733 -0.28067) (xy -0.22733 -0.27051)
						(xy -0.22606 -0.25908) (xy -0.22352 -0.24892) (xy -0.22225 -0.23876) (xy -0.21844 -0.22733) (xy -0.2159 -0.21717)
						(xy -0.21209 -0.20701) (xy -0.20701 -0.19685) (xy -0.2032 -0.18796) (xy -0.19812 -0.1778) (xy -0.17272 -0.14224)
						(xy -0.1651 -0.13462) (xy -0.1651 0.7366) (xy -0.16256 0.76835) (xy -0.1524 0.8001) (xy -0.13716 0.82804)
						(xy -0.11684 0.85344) (xy -0.09144 0.87376) (xy -0.0635 0.889) (xy -0.03175 0.89916) (xy 0 0.9017)
						(xy 0.03175 0.89916) (xy 0.0635 0.889) (xy 0.09144 0.87376) (xy 0.11684 0.85344) (xy 0.13716 0.82804)
						(xy 0.1524 0.8001) (xy 0.16256 0.76835) (xy 0.1651 0.7366) (xy 0.1651 -0.13462) (xy 0.17272 -0.14224)
						(xy 0.19812 -0.1778) (xy 0.2032 -0.18796) (xy 0.20701 -0.19685) (xy 0.21209 -0.20701) (xy 0.2159 -0.21717)
						(xy 0.21844 -0.22733) (xy 0.22225 -0.23876) (xy 0.22352 -0.24892) (xy 0.22606 -0.25908) (xy 0.22733 -0.27051)
						(xy 0.22733 -0.28067) (xy 0.2286 -0.2921) (xy 0.22733 -0.30353) (xy 0.22733 -0.31369) (xy 0.22606 -0.32512)
						(xy 0.22352 -0.33528) (xy 0.22225 -0.34544) (xy 0.21844 -0.35687) (xy 0.2159 -0.36703) (xy 0.21209 -0.37719)
						(xy 0.20701 -0.38735) (xy 0.2032 -0.39624) (xy 0.19812 -0.4064) (xy 0.17272 -0.44196) (xy 0.1651 -0.44958)
						(xy 0.1651 -0.7366) (xy 0.16256 -0.76835) (xy 0.1524 -0.8001) (xy 0.13716 -0.82804) (xy 0.11684 -0.85344)
						(xy 0.09144 -0.87376) (xy 0.0635 -0.889) (xy 0.03175 -0.89916)
					)
					(width 0)
					(fill yes)
				)
			)
		)
		(pad "90" smd custom
			(at -2.549906 4.100068)
			(size 0.1143 0.1143)
			(layers "B.Cu" "B.Mask" "B.Paste")
			(net "M_A_MA14")
			(options
				(clearance outline)
				(anchor circle)
			)
			(primitives
				(gr_poly
					(pts
						(xy 0 -0.9017) (xy -0.03175 -0.89916) (xy -0.0635 -0.889) (xy -0.09144 -0.87376) (xy -0.11684 -0.85344)
						(xy -0.13716 -0.82804) (xy -0.1524 -0.8001) (xy -0.16256 -0.76835) (xy -0.1651 -0.7366) (xy -0.1651 0.13462)
						(xy -0.17272 0.14224) (xy -0.19812 0.1778) (xy -0.2032 0.18796) (xy -0.20701 0.19685) (xy -0.21209 0.20701)
						(xy -0.2159 0.21717) (xy -0.21844 0.22733) (xy -0.22225 0.23876) (xy -0.22352 0.24892) (xy -0.22606 0.25908)
						(xy -0.22733 0.27051) (xy -0.22733 0.28067) (xy -0.2286 0.2921) (xy -0.22733 0.30353) (xy -0.22733 0.31369)
						(xy -0.22606 0.32512) (xy -0.22352 0.33528) (xy -0.22225 0.34544) (xy -0.21844 0.35687) (xy -0.2159 0.36703)
						(xy -0.21209 0.37719) (xy -0.20701 0.38735) (xy -0.2032 0.39624) (xy -0.19812 0.4064) (xy -0.17272 0.44196)
						(xy -0.1651 0.44958) (xy -0.1651 0.7366) (xy -0.16256 0.76835) (xy -0.1524 0.8001) (xy -0.13716 0.82804)
						(xy -0.11684 0.85344) (xy -0.09144 0.87376) (xy -0.0635 0.889) (xy -0.03175 0.89916) (xy 0 0.9017)
						(xy 0.03175 0.89916) (xy 0.0635 0.889) (xy 0.09144 0.87376) (xy 0.11684 0.85344) (xy 0.13716 0.82804)
						(xy 0.1524 0.8001) (xy 0.16256 0.76835) (xy 0.1651 0.7366) (xy 0.1651 0.44958) (xy 0.17272 0.44196)
						(xy 0.19812 0.4064) (xy 0.2032 0.39624) (xy 0.20701 0.38735) (xy 0.21209 0.37719) (xy 0.2159 0.36703)
						(xy 0.21844 0.35687) (xy 0.22225 0.34544) (xy 0.22352 0.33528) (xy 0.22606 0.32512) (xy 0.22733 0.31369)
						(xy 0.22733 0.30353) (xy 0.2286 0.2921) (xy 0.22733 0.28067) (xy 0.22733 0.27051) (xy 0.22606 0.25908)
						(xy 0.22352 0.24892) (xy 0.22225 0.23876) (xy 0.21844 0.22733) (xy 0.2159 0.21717) (xy 0.21209 0.20701)
						(xy 0.20701 0.19685) (xy 0.2032 0.18796) (xy 0.19812 0.1778) (xy 0.17272 0.14224) (xy 0.1651 0.13462)
						(xy 0.1651 -0.7366) (xy 0.16256 -0.76835) (xy 0.1524 -0.8001) (xy 0.13716 -0.82804) (xy 0.11684 -0.85344)
						(xy 0.09144 -0.87376) (xy 0.0635 -0.889) (xy 0.03175 -0.89916)
					)
					(width 0)
					(fill yes)
				)
			)
		)
	)
)
